# T6G (Grand Teton) — schematic netlist excerpt (pin names and nets, part order shuffled) for the footprints in the layout excerpt that follows; sources: Cadence DE-HDL packaged netlist, KiCad conversion of 04192023_DAF0TMB3IC0_F0TG_MB_C_brd_V02_OCP.brd

R414  Q_RES  2.2K 5% CHIP  pkg 0402LF  page 27 : A = CPU0_XTRIG_L5 ; B = PVDD18_S5_P0
C2665  Q_CAP  22UF 4V 20% X6S  pkg C0402  page 75 : A = PVDD18_S5_P1 ; B = GND
R1410  Q_RES  1K 1% CHIP  pkg 0201LF  page 185 : A = P1V8_CPU0_RT_1D ; B = SMB_RT_CPU0_P0_ROM_MUX_1D_SDA

(kicad_pcb
	(version 20260206)
	(generator "pcbnew")
	(generator_version "10.0")
	(general
		(thickness 1.6)
		(legacy_teardrops no)
	)
	(paper "A4")
	(title_block
		(title "04192023_DAF0TMB3IC0_F0TG_MB_C_brd_V02_OCP.brd")
		(comment 1 "Grand Teton / footprints 8003-8005 of 8354")
	)
	(layers
		(0 "F.Cu" signal "TOP")
		(4 "In1.Cu" signal "GND")
		(6 "In2.Cu" signal "IN1")
		(8 "In3.Cu" signal "GND1")
		(10 "In4.Cu" signal "IN2")
		(12 "In5.Cu" signal "GND2")
		(14 "In6.Cu" signal "IN3")
		(16 "In7.Cu" signal "GND3")
		(18 "In8.Cu" signal "VCC")
		(20 "In9.Cu" signal "VCC1")
		(22 "In10.Cu" signal "GND4")
		(24 "In11.Cu" signal "IN4")
		(26 "In12.Cu" signal "GND5")
		(28 "In13.Cu" signal "IN5")
		(30 "In14.Cu" signal "GND6")
		(32 "In15.Cu" signal "IN6")
		(34 "In16.Cu" signal "GND7")
		(2 "B.Cu" signal "BOTTOM")
		(9 "F.Adhes" user "F.Adhesive")
		(11 "B.Adhes" user "B.Adhesive")
		(13 "F.Paste" user "Package Geometry/Pastemask Top")
		(15 "B.Paste" user "Package Geometry/Pastemask Bottom")
		(5 "F.SilkS" user "Ref Des/Silkscreen Top")
		(7 "B.SilkS" user "Ref Des/Silkscreen Bottom")
		(1 "F.Mask" user "Board Geometry/Soldermask Top")
		(3 "B.Mask" user "Board Geometry/Soldermask Bottom")
		(17 "Dwgs.User" user "User.Drawings")
		(19 "Cmts.User" user "User.Comments")
		(21 "Eco1.User" user "User.Eco1")
		(23 "Eco2.User" user "User.Eco2")
		(25 "Edge.Cuts" user "Board Geometry/Outline")
		(27 "Margin" user)
		(31 "F.CrtYd" user "Package Geometry/Place Bound Top")
		(29 "B.CrtYd" user "Package Geometry/Place Bound Bottom")
		(35 "F.Fab" user "Ref Des/Assembly Top")
		(33 "B.Fab" user "Ref Des/Assembly Bottom")
	)
	(footprint ""
		(layer "B.Cu")
		(at 301.535338 -424.449748 -90)
		(property "Reference" "R1410"
			(at 0 0 90)
			(layer "B.SilkS")
			(hide yes)
			(effects
				(font
					(size 1.27 1.27)
				)
				(justify mirror)
			)
		)
		(property "Value" ""
			(at 0 0 90)
			(layer "B.Fab")
			(effects
				(font
					(size 1.27 1.27)
				)
				(justify mirror)
			)
		)
		(duplicate_pad_numbers_are_jumpers no)
		(fp_line
			(start -0.32512 0.175006)
			(end 0.32512 0.175006)
			(stroke
				(width 0.1)
				(type default)
			)
			(layer "B.Fab")
		)
		(fp_line
			(start 0.32512 0.175006)
			(end 0.32512 -0.175006)
			(stroke
				(width 0.1)
				(type default)
			)
			(layer "B.Fab")
		)
		(fp_line
			(start -0.32512 -0.175006)
			(end -0.32512 0.175006)
			(stroke
				(width 0.1)
				(type default)
			)
			(layer "B.Fab")
		)
		(fp_line
			(start 0.32512 -0.175006)
			(end -0.32512 -0.175006)
			(stroke
				(width 0.1)
				(type default)
			)
			(layer "B.Fab")
		)
		(pad "1" smd rect
			(at 0.2667 0 90)
			(size 0.3048 0.381)
			(layers "B.Cu" "B.Mask" "B.Paste")
			(net "P1V8_CPU0_RT_1D")
		)
		(pad "2" smd rect
			(at -0.2667 0 270)
			(size 0.3048 0.381)
			(layers "B.Cu" "B.Mask" "B.Paste")
			(net "SMB_RT_CPU0_P0_ROM_MUX_1D_SDA")
		)
	)
	(footprint ""
		(layer "B.Cu")
		(at 100.881434 -252.599952 180)
		(property "Reference" "C2665"
			(at 0 0 0)
			(layer "B.SilkS")
			(hide yes)
			(effects
				(font
					(size 1.27 1.27)
				)
				(justify mirror)
			)
		)
		(property "Value" ""
			(at 0 0 0)
			(layer "B.Fab")
			(effects
				(font
					(size 1.27 1.27)
				)
				(justify mirror)
			)
		)
		(duplicate_pad_numbers_are_jumpers no)
		(fp_line
			(start 0.7874 0.4064)
			(end 0.7874 -0.4064)
			(stroke
				(width 0.1524)
				(type default)
			)
			(layer "B.SilkS")
		)
		(fp_line
			(start 0.7874 -0.4064)
			(end -0.7874 -0.4064)
			(stroke
				(width 0.1524)
				(type default)
			)
			(layer "B.SilkS")
		)
		(fp_line
			(start -0.7874 0.4064)
			(end 0.7874 0.4064)
			(stroke
				(width 0.1524)
				(type default)
			)
			(layer "B.SilkS")
		)
		(fp_line
			(start -0.7874 -0.4064)
			(end -0.7874 0.4064)
			(stroke
				(width 0.1524)
				(type default)
			)
			(layer "B.SilkS")
		)
		(fp_line
			(start 0.67945 0.3048)
			(end 0.67945 -0.305054)
			(stroke
				(width 0.1)
				(type default)
			)
			(layer "B.Fab")
		)
		(fp_line
			(start 0.67945 -0.305054)
			(end 0.12065 -0.305054)
			(stroke
				(width 0.1)
				(type default)
			)
			(layer "B.Fab")
		)
		(fp_line
			(start 0.12065 0.3048)
			(end 0.67945 0.3048)
			(stroke
				(width 0.1)
				(type default)
			)
			(layer "B.Fab")
		)
		(fp_line
			(start 0.12065 0.2794)
			(end 0.12065 0.3048)
			(stroke
				(width 0.1)
				(type default)
			)
			(layer "B.Fab")
		)
		(fp_line
			(start 0.12065 -0.2794)
			(end -0.12065 -0.2794)
			(stroke
				(width 0.1)
				(type default)
			)
			(layer "B.Fab")
		)
		(fp_line
			(start 0.12065 -0.305054)
			(end 0.12065 -0.2794)
			(stroke
				(width 0.1)
				(type default)
			)
			(layer "B.Fab")
		)
		(fp_line
			(start -0.120396 0.3048)
			(end -0.120396 0.2794)
			(stroke
				(width 0.1)
				(type default)
			)
			(layer "B.Fab")
		)
		(fp_line
			(start -0.120396 0.2794)
			(end 0.12065 0.2794)
			(stroke
				(width 0.1)
				(type default)
			)
			(layer "B.Fab")
		)
		(fp_line
			(start -0.12065 -0.2794)
			(end -0.12065 -0.3048)
			(stroke
				(width 0.1)
				(type default)
			)
			(layer "B.Fab")
		)
		(fp_line
			(start -0.12065 -0.3048)
			(end -0.67945 -0.3048)
			(stroke
				(width 0.1)
				(type default)
			)
			(layer "B.Fab")
		)
		(fp_line
			(start -0.67945 0.3048)
			(end -0.120396 0.3048)
			(stroke
				(width 0.1)
				(type default)
			)
			(layer "B.Fab")
		)
		(fp_line
			(start -0.67945 -0.3048)
			(end -0.67945 0.3048)
			(stroke
				(width 0.1)
				(type default)
			)
			(layer "B.Fab")
		)
		(pad "1" smd circle
			(at 0.40005 0)
			(size 0 0)
			(layers "B.Cu" "B.Mask" "B.Paste")
			(net "PVDD18_S5_P1")
		)
		(pad "2" smd circle
			(at -0.40005 0)
			(size 0 0)
			(layers "B.Cu" "B.Mask" "B.Paste")
			(net "GND")
		)
	)
	(footprint ""
		(layer "B.Cu")
		(at 326.815958 -202.113896 90)
		(property "Reference" "R414"
			(at 0 0 90)
			(layer "B.SilkS")
			(hide yes)
			(effects
				(font
					(size 1.27 1.27)
				)
				(justify mirror)
			)
		)
		(property "Value" ""
			(at 0 0 90)
			(layer "B.Fab")
			(effects
				(font
					(size 1.27 1.27)
				)
				(justify mirror)
			)
		)
		(duplicate_pad_numbers_are_jumpers no)
		(fp_line
			(start 0.7874 -0.4064)
			(end -0.7874 -0.4064)
			(stroke
				(width 0.1524)
				(type default)
			)
			(layer "B.SilkS")
		)
		(fp_line
			(start -0.7874 -0.4064)
			(end -0.7874 0.4064)
			(stroke
				(width 0.1524)
				(type default)
			)
			(layer "B.SilkS")
		)
		(fp_line
			(start 0.7874 0.4064)
			(end 0.7874 -0.4064)
			(stroke
				(width 0.1524)
				(type default)
			)
			(layer "B.SilkS")
		)
		(fp_line
			(start -0.7874 0.4064)
			(end 0.7874 0.4064)
			(stroke
				(width 0.1524)
				(type default)
			)
			(layer "B.SilkS")
		)
		(fp_line
			(start 0.67945 -0.305054)
			(end 0.12065 -0.305054)
			(stroke
				(width 0.1)
				(type default)
			)
			(layer "B.Fab")
		)
		(fp_line
			(start 0.12065 -0.305054)
			(end 0.12065 -0.2794)
			(stroke
				(width 0.1)
				(type default)
			)
			(layer "B.Fab")
		)
		(fp_line
			(start -0.12065 -0.3048)
			(end -0.67945 -0.3048)
			(stroke
				(width 0.1)
				(type default)
			)
			(layer "B.Fab")
		)
		(fp_line
			(start -0.67945 -0.3048)
			(end -0.67945 0.3048)
			(stroke
				(width 0.1)
				(type default)
			)
			(layer "B.Fab")
		)
		(fp_line
			(start 0.12065 -0.2794)
			(end -0.12065 -0.2794)
			(stroke
				(width 0.1)
				(type default)
			)
			(layer "B.Fab")
		)
		(fp_line
			(start -0.12065 -0.2794)
			(end -0.12065 -0.3048)
			(stroke
				(width 0.1)
				(type default)
			)
			(layer "B.Fab")
		)
		(fp_line
			(start 0.12065 0.2794)
			(end 0.12065 0.3048)
			(stroke
				(width 0.1)
				(type default)
			)
			(layer "B.Fab")
		)
		(fp_line
			(start -0.120396 0.2794)
			(end 0.12065 0.2794)
			(stroke
				(width 0.1)
				(type default)
			)
			(layer "B.Fab")
		)
		(fp_line
			(start 0.67945 0.3048)
			(end 0.67945 -0.305054)
			(stroke
				(width 0.1)
				(type default)
			)
			(layer "B.Fab")
		)
		(fp_line
			(start 0.12065 0.3048)
			(end 0.67945 0.3048)
			(stroke
				(width 0.1)
				(type default)
			)
			(layer "B.Fab")
		)
		(fp_line
			(start -0.120396 0.3048)
			(end -0.120396 0.2794)
			(stroke
				(width 0.1)
				(type default)
			)
			(layer "B.Fab")
		)
		(fp_line
			(start -0.67945 0.3048)
			(end -0.120396 0.3048)
			(stroke
				(width 0.1)
				(type default)
			)
			(layer "B.Fab")
		)
		(pad "1" smd circle
			(at 0.40005 0 270)
			(size 0 0)
			(layers "B.Cu" "B.Mask" "B.Paste")
			(net "CPU0_XTRIG_L5")
		)
		(pad "2" smd circle
			(at -0.40005 0 270)
			(size 0 0)
			(layers "B.Cu" "B.Mask" "B.Paste")
			(net "PVDD18_S5_P0")
		)
	)
)
